(kicad_pcb
	(version 20260206)
	(generator "pcbnew")
	(generator_version "10.0")
	(general
		(thickness 1.6)
		(legacy_teardrops no)
	)
	(paper "A4")
	(title_block
		(title "Bryce Canyon_IOM_M2_16342-2_OCP.brd")
		(comment 1 "Bryce Canyon / footprints 970-976 of 1146")
	)
	(layers
		(0 "F.Cu" signal "TOP")
		(4 "In1.Cu" signal "L2GND")
		(6 "In2.Cu" signal "L3")
		(8 "In3.Cu" signal "L4VCC")
		(10 "In4.Cu" signal "L5VCC")
		(12 "In5.Cu" signal "L6")
		(14 "In6.Cu" signal "L7GND")
		(2 "B.Cu" signal "BOTTOM")
		(9 "F.Adhes" user "F.Adhesive")
		(11 "B.Adhes" user "B.Adhesive")
		(13 "F.Paste" user "Package Geometry/Pastemask Top")
		(15 "B.Paste" user "Package Geometry/Pastemask Bottom")
		(5 "F.SilkS" user "Ref Des/Silkscreen Top")
		(7 "B.SilkS" user "Ref Des/Silkscreen Bottom")
		(1 "F.Mask" user "Board Geometry/Soldermask Top")
		(3 "B.Mask" user "Board Geometry/Soldermask Bottom")
		(17 "Dwgs.User" user "User.Drawings")
		(19 "Cmts.User" user "User.Comments")
		(21 "Eco1.User" user "User.Eco1")
		(23 "Eco2.User" user "User.Eco2")
		(25 "Edge.Cuts" user "Board Geometry/Outline")
		(27 "Margin" user)
		(31 "F.CrtYd" user "Package Geometry/Place Bound Top")
		(29 "B.CrtYd" user "Package Geometry/Place Bound Bottom")
		(35 "F.Fab" user "Ref Des/Assembly Top")
		(33 "B.Fab" user "Ref Des/Assembly Bottom")
	)
	(footprint ""
		(layer "B.Cu")
		(at 40.281606 -132.286248 90)
		(property "Reference" "R370"
			(at 0 0 90)
			(layer "B.SilkS")
			(hide yes)
			(effects
				(font
					(size 1.27 1.27)
				)
				(justify mirror)
			)
		)
		(property "Value" "4K7R2F-GP"
			(at -0.064008 -3.993896 90)
			(unlocked yes)
			(layer "B.Fab")
			(hide yes)
			(effects
				(font
					(size 1.016 1.016)
					(thickness 0.1524)
				)
				(justify mirror)
			)
		)
		(property "Device Type" "R402H16"
			(at -0.064008 -5.517896 90)
			(unlocked yes)
			(layer "B.Fab")
			(hide yes)
			(effects
				(font
					(size 1.016 1.016)
					(thickness 0.1524)
				)
				(justify mirror)
			)
		)
		(duplicate_pad_numbers_are_jumpers no)
		(fp_line
			(start 0.508 -0.9398)
			(end 0.508 0.9398)
			(stroke
				(width 0.1524)
				(type default)
			)
			(layer "B.SilkS")
		)
		(fp_line
			(start -0.508 -0.9398)
			(end 0.508 -0.9398)
			(stroke
				(width 0.1524)
				(type default)
			)
			(layer "B.SilkS")
		)
		(fp_rect
			(start 0.508 0.9398)
			(end -0.508 -0.9398)
			(stroke
				(width 0)
				(type default)
			)
			(fill no)
			(layer "B.CrtYd")
		)
		(fp_rect
			(start 0.508 0.9398)
			(end -0.508 -0.9398)
			(stroke
				(width 0)
				(type default)
			)
			(fill no)
			(layer "B.Fab")
		)
		(pad "1" smd custom
			(at 0 -0.4445 270)
			(size 0.1397 0.1397)
			(layers "B.Cu" "B.Mask" "B.Paste")
			(net "P3V3_STBY")
			(options
				(clearance outline)
				(anchor circle)
			)
			(primitives
				(gr_poly
					(pts
						(arc
							(start -0.1778 0.2794)
							(mid -0.249642 0.249642)
							(end -0.2794 0.1778)
						)
						(arc
							(start -0.2794 -0.1778)
							(mid -0.249642 -0.249642)
							(end -0.1778 -0.2794)
						)
						(arc
							(start 0.1778 -0.2794)
							(mid 0.249642 -0.249642)
							(end 0.2794 -0.1778)
						)
						(arc
							(start 0.2794 0.1778)
							(mid 0.249642 0.249642)
							(end 0.1778 0.2794)
						)
					)
					(width 0)
					(fill yes)
				)
			)
		)
		(pad "2" smd custom
			(at 0 0.4445 270)
			(size 0.1397 0.1397)
			(layers "B.Cu" "B.Mask" "B.Paste")
			(net "BMC_SPI_MOSI")
			(options
				(clearance outline)
				(anchor circle)
			)
			(primitives
				(gr_poly
					(pts
						(arc
							(start -0.1778 0.2794)
							(mid -0.249642 0.249642)
							(end -0.2794 0.1778)
						)
						(arc
							(start -0.2794 -0.1778)
							(mid -0.249642 -0.249642)
							(end -0.1778 -0.2794)
						)
						(arc
							(start 0.1778 -0.2794)
							(mid 0.249642 -0.249642)
							(end 0.2794 -0.1778)
						)
						(arc
							(start 0.2794 0.1778)
							(mid 0.249642 0.249642)
							(end 0.1778 0.2794)
						)
					)
					(width 0)
					(fill yes)
				)
			)
		)
	)
	(footprint ""
		(layer "B.Cu")
		(at 132.41782 -21.30552 180)
		(property "Reference" "R744"
			(at 0 0 0)
			(layer "B.SilkS")
			(hide yes)
			(effects
				(font
					(size 1.27 1.27)
				)
				(justify mirror)
			)
		)
		(property "Value" "11KR2F-L-GP"
			(at -0.064008 -3.993896 180)
			(unlocked yes)
			(layer "B.Fab")
			(hide yes)
			(effects
				(font
					(size 1.016 1.016)
					(thickness 0.1524)
				)
				(justify mirror)
			)
		)
		(property "Device Type" "R402H16"
			(at -0.064008 -5.517896 180)
			(unlocked yes)
			(layer "B.Fab")
			(hide yes)
			(effects
				(font
					(size 1.016 1.016)
					(thickness 0.1524)
				)
				(justify mirror)
			)
		)
		(duplicate_pad_numbers_are_jumpers no)
		(fp_line
			(start 0.508 -0.9398)
			(end 0.508 0.9398)
			(stroke
				(width 0.1524)
				(type default)
			)
			(layer "B.SilkS")
		)
		(fp_line
			(start -0.508 -0.9398)
			(end 0.508 -0.9398)
			(stroke
				(width 0.1524)
				(type default)
			)
			(layer "B.SilkS")
		)
		(fp_rect
			(start 0.508 0.9398)
			(end -0.508 -0.9398)
			(stroke
				(width 0)
				(type default)
			)
			(fill no)
			(layer "B.CrtYd")
		)
		(fp_rect
			(start 0.508 0.9398)
			(end -0.508 -0.9398)
			(stroke
				(width 0)
				(type default)
			)
			(fill no)
			(layer "B.Fab")
		)
		(pad "1" smd custom
			(at 0 -0.4445)
			(size 0.1397 0.1397)
			(layers "B.Cu" "B.Mask" "B.Paste")
			(net "IOM_ADM1278_EN")
			(options
				(clearance outline)
				(anchor circle)
			)
			(primitives
				(gr_poly
					(pts
						(arc
							(start -0.1778 0.2794)
							(mid -0.249642 0.249642)
							(end -0.2794 0.1778)
						)
						(arc
							(start -0.2794 -0.1778)
							(mid -0.249642 -0.249642)
							(end -0.1778 -0.2794)
						)
						(arc
							(start 0.1778 -0.2794)
							(mid 0.249642 -0.249642)
							(end 0.2794 -0.1778)
						)
						(arc
							(start 0.2794 0.1778)
							(mid 0.249642 0.249642)
							(end 0.1778 0.2794)
						)
					)
					(width 0)
					(fill yes)
				)
			)
		)
		(pad "2" smd custom
			(at 0 0.4445)
			(size 0.1397 0.1397)
			(layers "B.Cu" "B.Mask" "B.Paste")
			(net "GND")
			(options
				(clearance outline)
				(anchor circle)
			)
			(primitives
				(gr_poly
					(pts
						(arc
							(start -0.1778 0.2794)
							(mid -0.249642 0.249642)
							(end -0.2794 0.1778)
						)
						(arc
							(start -0.2794 -0.1778)
							(mid -0.249642 -0.249642)
							(end -0.1778 -0.2794)
						)
						(arc
							(start 0.1778 -0.2794)
							(mid 0.249642 -0.249642)
							(end 0.2794 -0.1778)
						)
						(arc
							(start 0.2794 0.1778)
							(mid 0.249642 0.249642)
							(end 0.1778 0.2794)
						)
					)
					(width 0)
					(fill yes)
				)
			)
		)
	)
	(footprint ""
		(layer "B.Cu")
		(at 89.916 -161.2646 180)
		(property "Reference" "C16"
			(at 0 0 0)
			(layer "B.SilkS")
			(hide yes)
			(effects
				(font
					(size 1.27 1.27)
				)
				(justify mirror)
			)
		)
		(property "Value" "SC1U16V3KX-5GP"
			(at 0 -2.8194 180)
			(unlocked yes)
			(layer "B.Fab")
			(hide yes)
			(effects
				(font
					(size 1.016 1.016)
					(thickness 0.1524)
				)
				(justify mirror)
			)
		)
		(property "Device Type" "C603H36"
			(at 0 -4.3434 180)
			(unlocked yes)
			(layer "B.Fab")
			(hide yes)
			(effects
				(font
					(size 1.016 1.016)
					(thickness 0.1524)
				)
				(justify mirror)
			)
		)
		(duplicate_pad_numbers_are_jumpers no)
		(fp_line
			(start -0.508 0)
			(end 0.508 0)
			(stroke
				(width 0.2032)
				(type default)
			)
			(layer "B.SilkS")
		)
		(fp_rect
			(start 0.5842 1.3335)
			(end -0.5842 -1.3335)
			(stroke
				(width 0)
				(type default)
			)
			(fill no)
			(layer "B.CrtYd")
		)
		(fp_rect
			(start 0.5842 1.3335)
			(end -0.5842 -1.3335)
			(stroke
				(width 0)
				(type default)
			)
			(fill no)
			(layer "B.Fab")
		)
		(pad "1" smd custom
			(at 0 -0.762)
			(size 0.2159 0.2159)
			(layers "B.Cu" "B.Mask" "B.Paste")
			(net "P3V3_STBY")
			(options
				(clearance outline)
				(anchor circle)
			)
			(primitives
				(gr_poly
					(pts
						(arc
							(start -0.3302 0.4318)
							(mid -0.402042 0.402042)
							(end -0.4318 0.3302)
						)
						(arc
							(start -0.4318 -0.3302)
							(mid -0.402042 -0.402042)
							(end -0.3302 -0.4318)
						)
						(arc
							(start 0.3302 -0.4318)
							(mid 0.402042 -0.402042)
							(end 0.4318 -0.3302)
						)
						(arc
							(start 0.4318 0.3302)
							(mid 0.402042 0.402042)
							(end 0.3302 0.4318)
						)
					)
					(width 0)
					(fill yes)
				)
			)
		)
		(pad "2" smd custom
			(at 0 0.762)
			(size 0.2159 0.2159)
			(layers "B.Cu" "B.Mask" "B.Paste")
			(net "GND")
			(options
				(clearance outline)
				(anchor circle)
			)
			(primitives
				(gr_poly
					(pts
						(arc
							(start -0.3302 0.4318)
							(mid -0.402042 0.402042)
							(end -0.4318 0.3302)
						)
						(arc
							(start -0.4318 -0.3302)
							(mid -0.402042 -0.402042)
							(end -0.3302 -0.4318)
						)
						(arc
							(start 0.3302 -0.4318)
							(mid 0.402042 -0.402042)
							(end 0.4318 -0.3302)
						)
						(arc
							(start 0.4318 0.3302)
							(mid 0.402042 0.402042)
							(end 0.3302 0.4318)
						)
					)
					(width 0)
					(fill yes)
				)
			)
		)
	)
	(footprint ""
		(layer "B.Cu")
		(at 87.8586 -147.124674 -90)
		(property "Reference" "R429"
			(at 0 0 90)
			(layer "B.SilkS")
			(hide yes)
			(effects
				(font
					(size 1.27 1.27)
				)
				(justify mirror)
			)
		)
		(property "Value" "4K7R2F-GP"
			(at -0.064008 -3.993896 270)
			(unlocked yes)
			(layer "B.Fab")
			(hide yes)
			(effects
				(font
					(size 1.016 1.016)
					(thickness 0.1524)
				)
				(justify mirror)
			)
		)
		(property "Device Type" "R402H16"
			(at -0.064008 -5.517896 270)
			(unlocked yes)
			(layer "B.Fab")
			(hide yes)
			(effects
				(font
					(size 1.016 1.016)
					(thickness 0.1524)
				)
				(justify mirror)
			)
		)
		(duplicate_pad_numbers_are_jumpers no)
		(fp_line
			(start -0.508 -0.9398)
			(end 0.508 -0.9398)
			(stroke
				(width 0.1524)
				(type default)
			)
			(layer "B.SilkS")
		)
		(fp_line
			(start 0.508 -0.9398)
			(end 0.508 0.9398)
			(stroke
				(width 0.1524)
				(type default)
			)
			(layer "B.SilkS")
		)
		(fp_rect
			(start 0.508 0.9398)
			(end -0.508 -0.9398)
			(stroke
				(width 0)
				(type default)
			)
			(fill no)
			(layer "B.CrtYd")
		)
		(fp_rect
			(start 0.508 0.9398)
			(end -0.508 -0.9398)
			(stroke
				(width 0)
				(type default)
			)
			(fill no)
			(layer "B.Fab")
		)
		(pad "1" smd custom
			(at 0 -0.4445 90)
			(size 0.1397 0.1397)
			(layers "B.Cu" "B.Mask" "B.Paste")
			(net "TCA9555_A1")
			(options
				(clearance outline)
				(anchor circle)
			)
			(primitives
				(gr_poly
					(pts
						(arc
							(start -0.1778 0.2794)
							(mid -0.249642 0.249642)
							(end -0.2794 0.1778)
						)
						(arc
							(start -0.2794 -0.1778)
							(mid -0.249642 -0.249642)
							(end -0.1778 -0.2794)
						)
						(arc
							(start 0.1778 -0.2794)
							(mid 0.249642 -0.249642)
							(end 0.2794 -0.1778)
						)
						(arc
							(start 0.2794 0.1778)
							(mid 0.249642 0.249642)
							(end 0.1778 0.2794)
						)
					)
					(width 0)
					(fill yes)
				)
			)
		)
		(pad "2" smd custom
			(at 0 0.4445 90)
			(size 0.1397 0.1397)
			(layers "B.Cu" "B.Mask" "B.Paste")
			(net "GND")
			(options
				(clearance outline)
				(anchor circle)
			)
			(primitives
				(gr_poly
					(pts
						(arc
							(start -0.1778 0.2794)
							(mid -0.249642 0.249642)
							(end -0.2794 0.1778)
						)
						(arc
							(start -0.2794 -0.1778)
							(mid -0.249642 -0.249642)
							(end -0.1778 -0.2794)
						)
						(arc
							(start 0.1778 -0.2794)
							(mid 0.249642 -0.249642)
							(end 0.2794 -0.1778)
						)
						(arc
							(start 0.2794 0.1778)
							(mid 0.249642 0.249642)
							(end 0.1778 0.2794)
						)
					)
					(width 0)
					(fill yes)
				)
			)
		)
	)
	(footprint ""
		(layer "B.Cu")
		(at 39.751254 -142.892018 180)
		(property "Reference" "R145"
			(at 0 0 0)
			(layer "B.SilkS")
			(hide yes)
			(effects
				(font
					(size 1.27 1.27)
				)
				(justify mirror)
			)
		)
		(property "Value" "240R2F-1-GP"
			(at -0.064008 -3.993896 180)
			(unlocked yes)
			(layer "B.Fab")
			(hide yes)
			(effects
				(font
					(size 1.016 1.016)
					(thickness 0.1524)
				)
				(justify mirror)
			)
		)
		(property "Device Type" "R402H16"
			(at -0.064008 -5.517896 180)
			(unlocked yes)
			(layer "B.Fab")
			(hide yes)
			(effects
				(font
					(size 1.016 1.016)
					(thickness 0.1524)
				)
				(justify mirror)
			)
		)
		(duplicate_pad_numbers_are_jumpers no)
		(fp_line
			(start 0.508 -0.9398)
			(end 0.508 0.9398)
			(stroke
				(width 0.1524)
				(type default)
			)
			(layer "B.SilkS")
		)
		(fp_line
			(start -0.508 -0.9398)
			(end 0.508 -0.9398)
			(stroke
				(width 0.1524)
				(type default)
			)
			(layer "B.SilkS")
		)
		(fp_rect
			(start 0.508 0.9398)
			(end -0.508 -0.9398)
			(stroke
				(width 0)
				(type default)
			)
			(fill no)
			(layer "B.CrtYd")
		)
		(fp_rect
			(start 0.508 0.9398)
			(end -0.508 -0.9398)
			(stroke
				(width 0)
				(type default)
			)
			(fill no)
			(layer "B.Fab")
		)
		(pad "1" smd custom
			(at 0 -0.4445)
			(size 0.1397 0.1397)
			(layers "B.Cu" "B.Mask" "B.Paste")
			(net "GND")
			(options
				(clearance outline)
				(anchor circle)
			)
			(primitives
				(gr_poly
					(pts
						(arc
							(start -0.1778 0.2794)
							(mid -0.249642 0.249642)
							(end -0.2794 0.1778)
						)
						(arc
							(start -0.2794 -0.1778)
							(mid -0.249642 -0.249642)
							(end -0.1778 -0.2794)
						)
						(arc
							(start 0.1778 -0.2794)
							(mid 0.249642 -0.249642)
							(end 0.2794 -0.1778)
						)
						(arc
							(start 0.2794 0.1778)
							(mid 0.249642 0.249642)
							(end 0.1778 0.2794)
						)
					)
					(width 0)
					(fill yes)
				)
			)
		)
		(pad "2" smd custom
			(at 0 0.4445)
			(size 0.1397 0.1397)
			(layers "B.Cu" "B.Mask" "B.Paste")
			(net "MIOZ")
			(options
				(clearance outline)
				(anchor circle)
			)
			(primitives
				(gr_poly
					(pts
						(arc
							(start -0.1778 0.2794)
							(mid -0.249642 0.249642)
							(end -0.2794 0.1778)
						)
						(arc
							(start -0.2794 -0.1778)
							(mid -0.249642 -0.249642)
							(end -0.1778 -0.2794)
						)
						(arc
							(start 0.1778 -0.2794)
							(mid 0.249642 -0.249642)
							(end 0.2794 -0.1778)
						)
						(arc
							(start 0.2794 0.1778)
							(mid 0.249642 0.249642)
							(end 0.1778 0.2794)
						)
					)
					(width 0)
					(fill yes)
				)
			)
		)
	)
	(footprint ""
		(layer "B.Cu")
		(at 39.456614 -156.177488 180)
		(property "Reference" "R316"
			(at 0 0 0)
			(layer "B.SilkS")
			(hide yes)
			(effects
				(font
					(size 1.27 1.27)
				)
				(justify mirror)
			)
		)
		(property "Value" "0R2J-2-GP"
			(at -0.064008 -3.993896 180)
			(unlocked yes)
			(layer "B.Fab")
			(hide yes)
			(effects
				(font
					(size 1.016 1.016)
					(thickness 0.1524)
				)
				(justify mirror)
			)
		)
		(property "Device Type" "R402H16"
			(at -0.064008 -5.517896 180)
			(unlocked yes)
			(layer "B.Fab")
			(hide yes)
			(effects
				(font
					(size 1.016 1.016)
					(thickness 0.1524)
				)
				(justify mirror)
			)
		)
		(duplicate_pad_numbers_are_jumpers no)
		(fp_line
			(start 0.508 -0.9398)
			(end 0.508 0.9398)
			(stroke
				(width 0.1524)
				(type default)
			)
			(layer "B.SilkS")
		)
		(fp_line
			(start -0.508 -0.9398)
			(end 0.508 -0.9398)
			(stroke
				(width 0.1524)
				(type default)
			)
			(layer "B.SilkS")
		)
		(fp_rect
			(start 0.508 0.9398)
			(end -0.508 -0.9398)
			(stroke
				(width 0)
				(type default)
			)
			(fill no)
			(layer "B.CrtYd")
		)
		(fp_rect
			(start 0.508 0.9398)
			(end -0.508 -0.9398)
			(stroke
				(width 0)
				(type default)
			)
			(fill no)
			(layer "B.Fab")
		)
		(pad "1" smd custom
			(at 0 -0.4445)
			(size 0.1397 0.1397)
			(layers "B.Cu" "B.Mask" "B.Paste")
			(net "BMC_RMT_HB")
			(options
				(clearance outline)
				(anchor circle)
			)
			(primitives
				(gr_poly
					(pts
						(arc
							(start -0.1778 0.2794)
							(mid -0.249642 0.249642)
							(end -0.2794 0.1778)
						)
						(arc
							(start -0.2794 -0.1778)
							(mid -0.249642 -0.249642)
							(end -0.1778 -0.2794)
						)
						(arc
							(start 0.1778 -0.2794)
							(mid 0.249642 -0.249642)
							(end 0.2794 -0.1778)
						)
						(arc
							(start 0.2794 0.1778)
							(mid 0.249642 0.249642)
							(end 0.1778 0.2794)
						)
					)
					(width 0)
					(fill yes)
				)
			)
		)
		(pad "2" smd custom
			(at 0 0.4445)
			(size 0.1397 0.1397)
			(layers "B.Cu" "B.Mask" "B.Paste")
			(net "BMC_RMT_HEARTBEAT")
			(options
				(clearance outline)
				(anchor circle)
			)
			(primitives
				(gr_poly
					(pts
						(arc
							(start -0.1778 0.2794)
							(mid -0.249642 0.249642)
							(end -0.2794 0.1778)
						)
						(arc
							(start -0.2794 -0.1778)
							(mid -0.249642 -0.249642)
							(end -0.1778 -0.2794)
						)
						(arc
							(start 0.1778 -0.2794)
							(mid 0.249642 -0.249642)
							(end 0.2794 -0.1778)
						)
						(arc
							(start 0.2794 0.1778)
							(mid 0.249642 0.249642)
							(end 0.1778 0.2794)
						)
					)
					(width 0)
					(fill yes)
				)
			)
		)
	)
	(footprint ""
		(layer "B.Cu")
		(at 78.68031 -152.908 180)
		(property "Reference" "R101"
			(at 0 0 0)
			(layer "B.SilkS")
			(hide yes)
			(effects
				(font
					(size 1.27 1.27)
				)
				(justify mirror)
			)
		)
		(property "Value" "0R2J-2-GP"
			(at -0.064008 -3.993896 180)
			(unlocked yes)
			(layer "B.Fab")
			(hide yes)
			(effects
				(font
					(size 1.016 1.016)
					(thickness 0.1524)
				)
				(justify mirror)
			)
		)
		(property "Device Type" "R402H16"
			(at -0.064008 -5.517896 180)
			(unlocked yes)
			(layer "B.Fab")
			(hide yes)
			(effects
				(font
					(size 1.016 1.016)
					(thickness 0.1524)
				)
				(justify mirror)
			)
		)
		(duplicate_pad_numbers_are_jumpers no)
		(fp_line
			(start 0.508 -0.9398)
			(end 0.508 0.9398)
			(stroke
				(width 0.1524)
				(type default)
			)
			(layer "B.SilkS")
		)
		(fp_line
			(start -0.508 -0.9398)
			(end 0.508 -0.9398)
			(stroke
				(width 0.1524)
				(type default)
			)
			(layer "B.SilkS")
		)
		(fp_rect
			(start 0.508 0.9398)
			(end -0.508 -0.9398)
			(stroke
				(width 0)
				(type default)
			)
			(fill no)
			(layer "B.CrtYd")
		)
		(fp_rect
			(start 0.508 0.9398)
			(end -0.508 -0.9398)
			(stroke
				(width 0)
				(type default)
			)
			(fill no)
			(layer "B.Fab")
		)
		(pad "1" smd custom
			(at 0 -0.4445)
			(size 0.1397 0.1397)
			(layers "B.Cu" "B.Mask" "B.Paste")
			(net "I2C_COMP_ALERT_N")
			(options
				(clearance outline)
				(anchor circle)
			)
			(primitives
				(gr_poly
					(pts
						(arc
							(start -0.1778 0.2794)
							(mid -0.249642 0.249642)
							(end -0.2794 0.1778)
						)
						(arc
							(start -0.2794 -0.1778)
							(mid -0.249642 -0.249642)
							(end -0.1778 -0.2794)
						)
						(arc
							(start 0.1778 -0.2794)
							(mid 0.249642 -0.249642)
							(end 0.2794 -0.1778)
						)
						(arc
							(start 0.2794 0.1778)
							(mid 0.249642 0.249642)
							(end 0.1778 0.2794)
						)
					)
					(width 0)
					(fill yes)
				)
			)
		)
		(pad "2" smd custom
			(at 0 0.4445)
			(size 0.1397 0.1397)
			(layers "B.Cu" "B.Mask" "B.Paste")
			(net "I2C_BMC_COMP_ALERT_N_R")
			(options
				(clearance outline)
				(anchor circle)
			)
			(primitives
				(gr_poly
					(pts
						(arc
							(start -0.1778 0.2794)
							(mid -0.249642 0.249642)
							(end -0.2794 0.1778)
						)
						(arc
							(start -0.2794 -0.1778)
							(mid -0.249642 -0.249642)
							(end -0.1778 -0.2794)
						)
						(arc
							(start 0.1778 -0.2794)
							(mid 0.249642 -0.249642)
							(end 0.2794 -0.1778)
						)
						(arc
							(start 0.2794 0.1778)
							(mid 0.249642 0.249642)
							(end 0.1778 0.2794)
						)
					)
					(width 0)
					(fill yes)
				)
			)
		)
	)
)
